(kicad_pcb
	(version 20260206)
	(generator "pcbnew")
	(generator_version "10.0")
	(general
		(thickness 1.6)
		(legacy_teardrops no)
	)
	(paper "A4")
	(title_block
		(title "04192023_DAF0TMB3IC0_F0TG_MB_C_brd_V02_OCP.brd")
		(comment 1 "Grand Teton / footprint 802 of 8354 (J68), pads 1-113 of 291")
	)
	(layers
		(0 "F.Cu" signal "TOP")
		(4 "In1.Cu" signal "GND")
		(6 "In2.Cu" signal "IN1")
		(8 "In3.Cu" signal "GND1")
		(10 "In4.Cu" signal "IN2")
		(12 "In5.Cu" signal "GND2")
		(14 "In6.Cu" signal "IN3")
		(16 "In7.Cu" signal "GND3")
		(18 "In8.Cu" signal "VCC")
		(20 "In9.Cu" signal "VCC1")
		(22 "In10.Cu" signal "GND4")
		(24 "In11.Cu" signal "IN4")
		(26 "In12.Cu" signal "GND5")
		(28 "In13.Cu" signal "IN5")
		(30 "In14.Cu" signal "GND6")
		(32 "In15.Cu" signal "IN6")
		(34 "In16.Cu" signal "GND7")
		(2 "B.Cu" signal "BOTTOM")
		(9 "F.Adhes" user "F.Adhesive")
		(11 "B.Adhes" user "B.Adhesive")
		(13 "F.Paste" user "Package Geometry/Pastemask Top")
		(15 "B.Paste" user "Package Geometry/Pastemask Bottom")
		(5 "F.SilkS" user "Ref Des/Silkscreen Top")
		(7 "B.SilkS" user "Ref Des/Silkscreen Bottom")
		(1 "F.Mask" user "Board Geometry/Soldermask Top")
		(3 "B.Mask" user "Board Geometry/Soldermask Bottom")
		(17 "Dwgs.User" user "User.Drawings")
		(19 "Cmts.User" user "User.Comments")
		(21 "Eco1.User" user "User.Eco1")
		(23 "Eco2.User" user "User.Eco2")
		(25 "Edge.Cuts" user "Board Geometry/Outline")
		(27 "Margin" user)
		(31 "F.CrtYd" user "Package Geometry/Place Bound Top")
		(29 "B.CrtYd" user "Package Geometry/Place Bound Bottom")
		(35 "F.Fab" user "Ref Des/Assembly Top")
		(33 "B.Fab" user "Ref Des/Assembly Bottom")
	)
	(footprint ""
		(layer "F.Cu")
		(at 437.05018 -255.560068 180)
		(property "Reference" "J68"
			(at 1.32334 -81.844388 0)
			(unlocked yes)
			(layer "F.SilkS")
			(effects
				(font
					(size 0.7874 0.5842)
					(thickness 0.1524)
				)
			)
		)
		(property "Value" ""
			(at 0 0 180)
			(layer "F.Fab")
			(effects
				(font
					(size 1.27 1.27)
				)
			)
		)
		(duplicate_pad_numbers_are_jumpers no)
		(pad "1" smd rect
			(at -2.050034 -63.324994 90)
			(size 0.519938 1.4986)
			(layers "F.Cu" "F.Mask" "F.Paste")
			(net "P12V_MEM_CPU0")
		)
		(pad "2" smd rect
			(at -2.050034 -62.47511 90)
			(size 0.519938 1.4986)
			(layers "F.Cu" "F.Mask" "F.Paste")
			(net "Net_2375")
		)
		(pad "3" smd rect
			(at -2.050034 -61.624972 90)
			(size 0.519938 1.4986)
			(layers "F.Cu" "F.Mask" "F.Paste")
			(net "P3V3_AUX")
		)
		(pad "4" smd rect
			(at -2.050034 -60.775088 90)
			(size 0.519938 1.4986)
			(layers "F.Cu" "F.Mask" "F.Paste")
			(net "I3C_SPD_DDRJ_CPU0_SCL")
		)
		(pad "5" smd rect
			(at -2.050034 -59.92495 90)
			(size 0.519938 1.4986)
			(layers "F.Cu" "F.Mask" "F.Paste")
			(net "I3C_SPD_DDRJ_CPU0_SDA")
		)
		(pad "6" smd rect
			(at -2.050034 -59.075066 90)
			(size 0.519938 1.4986)
			(layers "F.Cu" "F.Mask" "F.Paste")
			(net "GND")
		)
		(pad "7" smd rect
			(at -2.050034 -58.224928 90)
			(size 0.519938 1.4986)
			(layers "F.Cu" "F.Mask" "F.Paste")
			(net "M_J_CPU0_SA_DQ<0>")
		)
		(pad "8" smd rect
			(at -2.050034 -57.375044 90)
			(size 0.519938 1.4986)
			(layers "F.Cu" "F.Mask" "F.Paste")
			(net "GND")
		)
		(pad "9" smd rect
			(at -2.050034 -56.524906 90)
			(size 0.519938 1.4986)
			(layers "F.Cu" "F.Mask" "F.Paste")
			(net "M_J_CPU0_SA_DQ<1>")
		)
		(pad "10" smd rect
			(at -2.050034 -55.675022 90)
			(size 0.519938 1.4986)
			(layers "F.Cu" "F.Mask" "F.Paste")
			(net "GND")
		)
		(pad "11" smd rect
			(at -2.050034 -54.824884 90)
			(size 0.519938 1.4986)
			(layers "F.Cu" "F.Mask" "F.Paste")
			(net "M_J_CPU0_SA_DQS_DP<0>")
		)
		(pad "12" smd rect
			(at -2.050034 -53.975 90)
			(size 0.519938 1.4986)
			(layers "F.Cu" "F.Mask" "F.Paste")
			(net "M_J_CPU0_SA_DQS_DN<0>")
		)
		(pad "13" smd rect
			(at -2.050034 -53.125116 90)
			(size 0.519938 1.4986)
			(layers "F.Cu" "F.Mask" "F.Paste")
			(net "GND")
		)
		(pad "14" smd rect
			(at -2.050034 -52.274978 90)
			(size 0.519938 1.4986)
			(layers "F.Cu" "F.Mask" "F.Paste")
			(net "M_J_CPU0_SA_DQ<4>")
		)
		(pad "15" smd rect
			(at -2.050034 -51.425094 90)
			(size 0.519938 1.4986)
			(layers "F.Cu" "F.Mask" "F.Paste")
			(net "GND")
		)
		(pad "16" smd rect
			(at -2.050034 -50.574956 90)
			(size 0.519938 1.4986)
			(layers "F.Cu" "F.Mask" "F.Paste")
			(net "M_J_CPU0_SA_DQ<5>")
		)
		(pad "17" smd rect
			(at -2.050034 -49.725072 90)
			(size 0.519938 1.4986)
			(layers "F.Cu" "F.Mask" "F.Paste")
			(net "GND")
		)
		(pad "18" smd rect
			(at -2.050034 -48.874934 90)
			(size 0.519938 1.4986)
			(layers "F.Cu" "F.Mask" "F.Paste")
			(net "M_J_CPU0_SA_DQ<8>")
		)
		(pad "19" smd rect
			(at -2.050034 -48.02505 90)
			(size 0.519938 1.4986)
			(layers "F.Cu" "F.Mask" "F.Paste")
			(net "GND")
		)
		(pad "20" smd rect
			(at -2.050034 -47.174912 90)
			(size 0.519938 1.4986)
			(layers "F.Cu" "F.Mask" "F.Paste")
			(net "M_J_CPU0_SA_DQ<9>")
		)
		(pad "21" smd rect
			(at -2.050034 -46.325028 90)
			(size 0.519938 1.4986)
			(layers "F.Cu" "F.Mask" "F.Paste")
			(net "GND")
		)
		(pad "22" smd rect
			(at -2.050034 -45.47489 90)
			(size 0.519938 1.4986)
			(layers "F.Cu" "F.Mask" "F.Paste")
			(net "M_J_CPU0_SA_DQS_DP<1>")
		)
		(pad "23" smd rect
			(at -2.050034 -44.625006 90)
			(size 0.519938 1.4986)
			(layers "F.Cu" "F.Mask" "F.Paste")
			(net "M_J_CPU0_SA_DQS_DN<1>")
		)
		(pad "24" smd rect
			(at -2.050034 -43.775122 90)
			(size 0.519938 1.4986)
			(layers "F.Cu" "F.Mask" "F.Paste")
			(net "GND")
		)
		(pad "25" smd rect
			(at -2.050034 -42.924984 90)
			(size 0.519938 1.4986)
			(layers "F.Cu" "F.Mask" "F.Paste")
			(net "M_J_CPU0_SA_DQ<12>")
		)
		(pad "26" smd rect
			(at -2.050034 -42.0751 90)
			(size 0.519938 1.4986)
			(layers "F.Cu" "F.Mask" "F.Paste")
			(net "GND")
		)
		(pad "27" smd rect
			(at -2.050034 -41.224962 90)
			(size 0.519938 1.4986)
			(layers "F.Cu" "F.Mask" "F.Paste")
			(net "M_J_CPU0_SA_DQ<13>")
		)
		(pad "28" smd rect
			(at -2.050034 -40.375078 90)
			(size 0.519938 1.4986)
			(layers "F.Cu" "F.Mask" "F.Paste")
			(net "GND")
		)
		(pad "29" smd rect
			(at -2.050034 -39.52494 90)
			(size 0.519938 1.4986)
			(layers "F.Cu" "F.Mask" "F.Paste")
			(net "M_J_CPU0_SA_DQ<16>")
		)
		(pad "30" smd rect
			(at -2.050034 -38.675056 90)
			(size 0.519938 1.4986)
			(layers "F.Cu" "F.Mask" "F.Paste")
			(net "GND")
		)
		(pad "31" smd rect
			(at -2.050034 -37.824918 90)
			(size 0.519938 1.4986)
			(layers "F.Cu" "F.Mask" "F.Paste")
			(net "M_J_CPU0_SA_DQ<17>")
		)
		(pad "32" smd rect
			(at -2.050034 -36.975034 90)
			(size 0.519938 1.4986)
			(layers "F.Cu" "F.Mask" "F.Paste")
			(net "GND")
		)
		(pad "33" smd rect
			(at -2.050034 -36.124896 90)
			(size 0.519938 1.4986)
			(layers "F.Cu" "F.Mask" "F.Paste")
			(net "M_J_CPU0_SA_DQS_DP<2>")
		)
		(pad "34" smd rect
			(at -2.050034 -35.275012 90)
			(size 0.519938 1.4986)
			(layers "F.Cu" "F.Mask" "F.Paste")
			(net "M_J_CPU0_SA_DQS_DN<2>")
		)
		(pad "35" smd rect
			(at -2.050034 -34.425128 90)
			(size 0.519938 1.4986)
			(layers "F.Cu" "F.Mask" "F.Paste")
			(net "GND")
		)
		(pad "36" smd rect
			(at -2.050034 -33.57499 90)
			(size 0.519938 1.4986)
			(layers "F.Cu" "F.Mask" "F.Paste")
			(net "M_J_CPU0_SA_DQ<20>")
		)
		(pad "37" smd rect
			(at -2.050034 -32.725106 90)
			(size 0.519938 1.4986)
			(layers "F.Cu" "F.Mask" "F.Paste")
			(net "GND")
		)
		(pad "38" smd rect
			(at -2.050034 -31.874968 90)
			(size 0.519938 1.4986)
			(layers "F.Cu" "F.Mask" "F.Paste")
			(net "M_J_CPU0_SA_DQ<21>")
		)
		(pad "39" smd rect
			(at -2.050034 -31.025084 90)
			(size 0.519938 1.4986)
			(layers "F.Cu" "F.Mask" "F.Paste")
			(net "GND")
		)
		(pad "40" smd rect
			(at -2.050034 -30.174946 90)
			(size 0.519938 1.4986)
			(layers "F.Cu" "F.Mask" "F.Paste")
			(net "M_J_CPU0_SA_DQ<24>")
		)
		(pad "41" smd rect
			(at -2.050034 -29.325062 90)
			(size 0.519938 1.4986)
			(layers "F.Cu" "F.Mask" "F.Paste")
			(net "GND")
		)
		(pad "42" smd rect
			(at -2.050034 -28.474924 90)
			(size 0.519938 1.4986)
			(layers "F.Cu" "F.Mask" "F.Paste")
			(net "M_J_CPU0_SA_DQ<25>")
		)
		(pad "43" smd rect
			(at -2.050034 -27.62504 90)
			(size 0.519938 1.4986)
			(layers "F.Cu" "F.Mask" "F.Paste")
			(net "GND")
		)
		(pad "44" smd rect
			(at -2.050034 -26.774902 90)
			(size 0.519938 1.4986)
			(layers "F.Cu" "F.Mask" "F.Paste")
			(net "M_J_CPU0_SA_DQS_DP<3>")
		)
		(pad "45" smd rect
			(at -2.050034 -25.925018 90)
			(size 0.519938 1.4986)
			(layers "F.Cu" "F.Mask" "F.Paste")
			(net "M_J_CPU0_SA_DQS_DN<3>")
		)
		(pad "46" smd rect
			(at -2.050034 -25.07488 90)
			(size 0.519938 1.4986)
			(layers "F.Cu" "F.Mask" "F.Paste")
			(net "GND")
		)
		(pad "47" smd rect
			(at -2.050034 -24.224996 90)
			(size 0.519938 1.4986)
			(layers "F.Cu" "F.Mask" "F.Paste")
			(net "M_J_CPU0_SA_DQ<28>")
		)
		(pad "48" smd rect
			(at -2.050034 -23.375112 90)
			(size 0.519938 1.4986)
			(layers "F.Cu" "F.Mask" "F.Paste")
			(net "GND")
		)
		(pad "49" smd rect
			(at -2.050034 -22.524974 90)
			(size 0.519938 1.4986)
			(layers "F.Cu" "F.Mask" "F.Paste")
			(net "M_J_CPU0_SA_DQ<29>")
		)
		(pad "50" smd rect
			(at -2.050034 -21.67509 90)
			(size 0.519938 1.4986)
			(layers "F.Cu" "F.Mask" "F.Paste")
			(net "GND")
		)
		(pad "51" smd rect
			(at -2.050034 -20.824952 90)
			(size 0.519938 1.4986)
			(layers "F.Cu" "F.Mask" "F.Paste")
			(net "M_J_CPU0_SA_CB<0>")
		)
		(pad "52" smd rect
			(at -2.050034 -19.975068 90)
			(size 0.519938 1.4986)
			(layers "F.Cu" "F.Mask" "F.Paste")
			(net "GND")
		)
		(pad "53" smd rect
			(at -2.050034 -19.12493 90)
			(size 0.519938 1.4986)
			(layers "F.Cu" "F.Mask" "F.Paste")
			(net "M_J_CPU0_SA_CB<1>")
		)
		(pad "54" smd rect
			(at -2.050034 -18.275046 90)
			(size 0.519938 1.4986)
			(layers "F.Cu" "F.Mask" "F.Paste")
			(net "GND")
		)
		(pad "55" smd rect
			(at -2.050034 -17.424908 90)
			(size 0.519938 1.4986)
			(layers "F.Cu" "F.Mask" "F.Paste")
			(net "M_J_CPU0_SA_DQS_DP<4>")
		)
		(pad "56" smd rect
			(at -2.050034 -16.575024 90)
			(size 0.519938 1.4986)
			(layers "F.Cu" "F.Mask" "F.Paste")
			(net "M_J_CPU0_SA_DQS_DN<4>")
		)
		(pad "57" smd rect
			(at -2.050034 -15.724886 90)
			(size 0.519938 1.4986)
			(layers "F.Cu" "F.Mask" "F.Paste")
			(net "GND")
		)
		(pad "58" smd rect
			(at -2.050034 -14.875002 90)
			(size 0.519938 1.4986)
			(layers "F.Cu" "F.Mask" "F.Paste")
			(net "M_J_CPU0_SA_CB<4>")
		)
		(pad "59" smd rect
			(at -2.050034 -14.025118 90)
			(size 0.519938 1.4986)
			(layers "F.Cu" "F.Mask" "F.Paste")
			(net "GND")
		)
		(pad "60" smd rect
			(at -2.050034 -13.17498 90)
			(size 0.519938 1.4986)
			(layers "F.Cu" "F.Mask" "F.Paste")
			(net "M_J_CPU0_SA_CB<5>")
		)
		(pad "61" smd rect
			(at -2.050034 -12.325096 90)
			(size 0.519938 1.4986)
			(layers "F.Cu" "F.Mask" "F.Paste")
			(net "GND")
		)
		(pad "62" smd rect
			(at -2.050034 -11.474958 90)
			(size 0.519938 1.4986)
			(layers "F.Cu" "F.Mask" "F.Paste")
			(net "M_J_CPU0_ALERT_N")
		)
		(pad "63" smd rect
			(at -2.050034 -10.625074 90)
			(size 0.519938 1.4986)
			(layers "F.Cu" "F.Mask" "F.Paste")
			(net "GND")
		)
		(pad "64" smd rect
			(at -2.050034 -9.774936 90)
			(size 0.519938 1.4986)
			(layers "F.Cu" "F.Mask" "F.Paste")
			(net "M_J_CPU0_SA_CS_N<0>")
		)
		(pad "65" smd rect
			(at -2.050034 -8.925052 90)
			(size 0.519938 1.4986)
			(layers "F.Cu" "F.Mask" "F.Paste")
			(net "GND")
		)
		(pad "66" smd rect
			(at -2.050034 -8.074914 90)
			(size 0.519938 1.4986)
			(layers "F.Cu" "F.Mask" "F.Paste")
			(net "M_J_CPU0_SA_CA<0>")
		)
		(pad "67" smd rect
			(at -2.050034 -7.22503 90)
			(size 0.519938 1.4986)
			(layers "F.Cu" "F.Mask" "F.Paste")
			(net "GND")
		)
		(pad "68" smd rect
			(at -2.050034 -6.374892 90)
			(size 0.519938 1.4986)
			(layers "F.Cu" "F.Mask" "F.Paste")
			(net "M_J_CPU0_SA_CA<2>")
		)
		(pad "69" smd rect
			(at -2.050034 -5.525008 90)
			(size 0.519938 1.4986)
			(layers "F.Cu" "F.Mask" "F.Paste")
			(net "GND")
		)
		(pad "70" smd rect
			(at -2.050034 -4.675124 90)
			(size 0.519938 1.4986)
			(layers "F.Cu" "F.Mask" "F.Paste")
			(net "M_J_CPU0_SA_CA<4>")
		)
		(pad "71" smd rect
			(at -2.050034 -3.824986 90)
			(size 0.519938 1.4986)
			(layers "F.Cu" "F.Mask" "F.Paste")
			(net "GND")
		)
		(pad "72" smd rect
			(at -2.050034 -2.975102 90)
			(size 0.519938 1.4986)
			(layers "F.Cu" "F.Mask" "F.Paste")
			(net "M_J_CPU0_SA_CA<6>")
		)
		(pad "73" smd rect
			(at -2.050034 -2.124964 90)
			(size 0.519938 1.4986)
			(layers "F.Cu" "F.Mask" "F.Paste")
			(net "GND")
		)
		(pad "74" smd rect
			(at -2.050034 -1.27508 90)
			(size 0.519938 1.4986)
			(layers "F.Cu" "F.Mask" "F.Paste")
			(net "M_J_CPU0_SA_PAR")
		)
		(pad "75" smd rect
			(at -2.050034 -0.424942 90)
			(size 0.519938 1.4986)
			(layers "F.Cu" "F.Mask" "F.Paste")
			(net "GND")
		)
		(pad "76" smd rect
			(at -2.050034 5.525008 90)
			(size 0.519938 1.4986)
			(layers "F.Cu" "F.Mask" "F.Paste")
			(net "M_J_CPU0_SB_CA<0>")
		)
		(pad "77" smd rect
			(at -2.050034 6.374892 90)
			(size 0.519938 1.4986)
			(layers "F.Cu" "F.Mask" "F.Paste")
			(net "GND")
		)
		(pad "78" smd rect
			(at -2.050034 7.22503 90)
			(size 0.519938 1.4986)
			(layers "F.Cu" "F.Mask" "F.Paste")
			(net "M_J_CPU0_SB_CA<2>")
		)
		(pad "79" smd rect
			(at -2.050034 8.074914 90)
			(size 0.519938 1.4986)
			(layers "F.Cu" "F.Mask" "F.Paste")
			(net "GND")
		)
		(pad "80" smd rect
			(at -2.050034 8.925052 90)
			(size 0.519938 1.4986)
			(layers "F.Cu" "F.Mask" "F.Paste")
			(net "M_J_CPU0_SB_CA<4>")
		)
		(pad "81" smd rect
			(at -2.050034 9.774936 90)
			(size 0.519938 1.4986)
			(layers "F.Cu" "F.Mask" "F.Paste")
			(net "GND")
		)
		(pad "82" smd rect
			(at -2.050034 10.625074 90)
			(size 0.519938 1.4986)
			(layers "F.Cu" "F.Mask" "F.Paste")
			(net "M_J_CPU0_SB_CA<6>")
		)
		(pad "83" smd rect
			(at -2.050034 11.474958 90)
			(size 0.519938 1.4986)
			(layers "F.Cu" "F.Mask" "F.Paste")
			(net "GND")
		)
		(pad "84" smd rect
			(at -2.050034 12.325096 90)
			(size 0.519938 1.4986)
			(layers "F.Cu" "F.Mask" "F.Paste")
			(net "M_J_CPU0_SB_CS_N<0>")
		)
		(pad "85" smd rect
			(at -2.050034 13.17498 90)
			(size 0.519938 1.4986)
			(layers "F.Cu" "F.Mask" "F.Paste")
			(net "GND")
		)
		(pad "86" smd rect
			(at -2.050034 14.025118 90)
			(size 0.519938 1.4986)
			(layers "F.Cu" "F.Mask" "F.Paste")
			(net "M_J_CPU0_SA_RSP<0>")
		)
		(pad "87" smd rect
			(at -2.050034 14.875002 90)
			(size 0.519938 1.4986)
			(layers "F.Cu" "F.Mask" "F.Paste")
			(net "M_J_CPU0_SB_RSP<0>")
		)
		(pad "88" smd rect
			(at -2.050034 15.724886 90)
			(size 0.519938 1.4986)
			(layers "F.Cu" "F.Mask" "F.Paste")
			(net "GND")
		)
		(pad "89" smd rect
			(at -2.050034 16.575024 90)
			(size 0.519938 1.4986)
			(layers "F.Cu" "F.Mask" "F.Paste")
			(net "M_J_CPU0_SB_CB<4>")
		)
		(pad "90" smd rect
			(at -2.050034 17.424908 90)
			(size 0.519938 1.4986)
			(layers "F.Cu" "F.Mask" "F.Paste")
			(net "GND")
		)
		(pad "91" smd rect
			(at -2.050034 18.275046 90)
			(size 0.519938 1.4986)
			(layers "F.Cu" "F.Mask" "F.Paste")
			(net "M_J_CPU0_SB_CB<5>")
		)
		(pad "92" smd rect
			(at -2.050034 19.12493 90)
			(size 0.519938 1.4986)
			(layers "F.Cu" "F.Mask" "F.Paste")
			(net "GND")
		)
		(pad "93" smd rect
			(at -2.050034 19.975068 90)
			(size 0.519938 1.4986)
			(layers "F.Cu" "F.Mask" "F.Paste")
			(net "M_J_CPU0_SB_DQS_DP<9>")
		)
		(pad "94" smd rect
			(at -2.050034 20.824952 90)
			(size 0.519938 1.4986)
			(layers "F.Cu" "F.Mask" "F.Paste")
			(net "M_J_CPU0_SB_DQS_DN<9>")
		)
		(pad "95" smd rect
			(at -2.050034 21.67509 90)
			(size 0.519938 1.4986)
			(layers "F.Cu" "F.Mask" "F.Paste")
			(net "GND")
		)
		(pad "96" smd rect
			(at -2.050034 22.524974 90)
			(size 0.519938 1.4986)
			(layers "F.Cu" "F.Mask" "F.Paste")
			(net "M_J_CPU0_SB_CB<0>")
		)
		(pad "97" smd rect
			(at -2.050034 23.375112 90)
			(size 0.519938 1.4986)
			(layers "F.Cu" "F.Mask" "F.Paste")
			(net "GND")
		)
		(pad "98" smd rect
			(at -2.050034 24.224996 90)
			(size 0.519938 1.4986)
			(layers "F.Cu" "F.Mask" "F.Paste")
			(net "M_J_CPU0_SB_CB<1>")
		)
		(pad "99" smd rect
			(at -2.050034 25.07488 90)
			(size 0.519938 1.4986)
			(layers "F.Cu" "F.Mask" "F.Paste")
			(net "GND")
		)
		(pad "100" smd rect
			(at -2.050034 25.925018 90)
			(size 0.519938 1.4986)
			(layers "F.Cu" "F.Mask" "F.Paste")
			(net "M_J_CPU0_SB_DQ<0>")
		)
		(pad "101" smd rect
			(at -2.050034 26.774902 90)
			(size 0.519938 1.4986)
			(layers "F.Cu" "F.Mask" "F.Paste")
			(net "GND")
		)
		(pad "102" smd rect
			(at -2.050034 27.62504 90)
			(size 0.519938 1.4986)
			(layers "F.Cu" "F.Mask" "F.Paste")
			(net "M_J_CPU0_SB_DQ<1>")
		)
		(pad "103" smd rect
			(at -2.050034 28.474924 90)
			(size 0.519938 1.4986)
			(layers "F.Cu" "F.Mask" "F.Paste")
			(net "GND")
		)
		(pad "104" smd rect
			(at -2.050034 29.325062 90)
			(size 0.519938 1.4986)
			(layers "F.Cu" "F.Mask" "F.Paste")
			(net "M_J_CPU0_SB_DQS_DP<0>")
		)
		(pad "105" smd rect
			(at -2.050034 30.174946 90)
			(size 0.519938 1.4986)
			(layers "F.Cu" "F.Mask" "F.Paste")
			(net "M_J_CPU0_SB_DQS_DN<0>")
		)
		(pad "106" smd rect
			(at -2.050034 31.025084 90)
			(size 0.519938 1.4986)
			(layers "F.Cu" "F.Mask" "F.Paste")
			(net "GND")
		)
		(pad "107" smd rect
			(at -2.050034 31.874968 90)
			(size 0.519938 1.4986)
			(layers "F.Cu" "F.Mask" "F.Paste")
			(net "M_J_CPU0_SB_DQ<4>")
		)
		(pad "108" smd rect
			(at -2.050034 32.725106 90)
			(size 0.519938 1.4986)
			(layers "F.Cu" "F.Mask" "F.Paste")
			(net "GND")
		)
		(pad "109" smd rect
			(at -2.050034 33.57499 90)
			(size 0.519938 1.4986)
			(layers "F.Cu" "F.Mask" "F.Paste")
			(net "M_J_CPU0_SB_DQ<5>")
		)
		(pad "110" smd rect
			(at -2.050034 34.425128 90)
			(size 0.519938 1.4986)
			(layers "F.Cu" "F.Mask" "F.Paste")
			(net "GND")
		)
		(pad "111" smd rect
			(at -2.050034 35.275012 90)
			(size 0.519938 1.4986)
			(layers "F.Cu" "F.Mask" "F.Paste")
			(net "M_J_CPU0_SB_DQ<8>")
		)
		(pad "112" smd rect
			(at -2.050034 36.124896 90)
			(size 0.519938 1.4986)
			(layers "F.Cu" "F.Mask" "F.Paste")
			(net "GND")
		)
		(pad "113" smd rect
			(at -2.050034 36.975034 90)
			(size 0.519938 1.4986)
			(layers "F.Cu" "F.Mask" "F.Paste")
			(net "M_J_CPU0_SB_DQ<9>")
		)
	)
)
